(kicad_pcb
	(version 20260206)
	(generator "pcbnew")
	(generator_version "10.0")
	(general
		(thickness 1.6)
		(legacy_teardrops no)
	)
	(paper "A4")
	(title_block
		(title "Bryce Canyon_SCC_16316-1_OCP.brd")
		(comment 1 "Bryce Canyon / footprints 582-586 of 1561")
	)
	(layers
		(0 "F.Cu" signal "TOP")
		(4 "In1.Cu" signal "L2GND")
		(6 "In2.Cu" signal "L3")
		(8 "In3.Cu" signal "L4VCC")
		(10 "In4.Cu" signal "L5VCC")
		(12 "In5.Cu" signal "L6")
		(14 "In6.Cu" signal "L7GND")
		(2 "B.Cu" signal "BOTTOM")
		(9 "F.Adhes" user "F.Adhesive")
		(11 "B.Adhes" user "B.Adhesive")
		(13 "F.Paste" user "Package Geometry/Pastemask Top")
		(15 "B.Paste" user "Package Geometry/Pastemask Bottom")
		(5 "F.SilkS" user "Ref Des/Silkscreen Top")
		(7 "B.SilkS" user "Ref Des/Silkscreen Bottom")
		(1 "F.Mask" user "Board Geometry/Soldermask Top")
		(3 "B.Mask" user "Board Geometry/Soldermask Bottom")
		(17 "Dwgs.User" user "User.Drawings")
		(19 "Cmts.User" user "User.Comments")
		(21 "Eco1.User" user "User.Eco1")
		(23 "Eco2.User" user "User.Eco2")
		(25 "Edge.Cuts" user "Board Geometry/Outline")
		(27 "Margin" user)
		(31 "F.CrtYd" user "Package Geometry/Place Bound Top")
		(29 "B.CrtYd" user "Package Geometry/Place Bound Bottom")
		(35 "F.Fab" user "Ref Des/Assembly Top")
		(33 "B.Fab" user "Ref Des/Assembly Bottom")
	)
	(footprint ""
		(layer "F.Cu")
		(at 154.84348 -98.3361 -90)
		(property "Reference" "U21"
			(at 0 0 270)
			(layer "F.SilkS")
			(hide yes)
			(effects
				(font
					(size 1.27 1.27)
				)
			)
		)
		(property "Value" "TXS0102DCUR-1-GP"
			(at 0 -11.1252 270)
			(unlocked yes)
			(layer "F.Fab")
			(hide yes)
			(effects
				(font
					(size 1.016 1.016)
					(thickness 0.1524)
				)
			)
		)
		(property "Device Type" "SSOIC8-4H36"
			(at 0 -12.6492 270)
			(unlocked yes)
			(layer "F.Fab")
			(hide yes)
			(effects
				(font
					(size 1.016 1.016)
					(thickness 0.1524)
				)
			)
		)
		(duplicate_pad_numbers_are_jumpers no)
		(fp_line
			(start -1.2573 2.1844)
			(end -1.2573 -2.1844)
			(stroke
				(width 0.1524)
				(type default)
			)
			(layer "F.SilkS")
		)
		(fp_line
			(start 1.2573 2.1844)
			(end -1.2573 2.1844)
			(stroke
				(width 0.1524)
				(type default)
			)
			(layer "F.SilkS")
		)
		(fp_line
			(start -1.2954 0.4572)
			(end -1.2954 2.159)
			(stroke
				(width 0.4064)
				(type default)
			)
			(layer "F.SilkS")
		)
		(fp_line
			(start -1.2065 0.2667)
			(end -1.27 0.2667)
			(stroke
				(width 0.1524)
				(type default)
			)
			(layer "F.SilkS")
		)
		(fp_line
			(start -0.9017 -0.0381)
			(end -1.2065 0.2667)
			(stroke
				(width 0.1524)
				(type default)
			)
			(layer "F.SilkS")
		)
		(fp_line
			(start -1.2573 -0.3556)
			(end -1.2192 -0.3556)
			(stroke
				(width 0.1524)
				(type default)
			)
			(layer "F.SilkS")
		)
		(fp_line
			(start -1.2192 -0.3556)
			(end -0.9017 -0.0381)
			(stroke
				(width 0.1524)
				(type default)
			)
			(layer "F.SilkS")
		)
		(fp_line
			(start -1.2573 -2.1844)
			(end 1.2573 -2.1844)
			(stroke
				(width 0.1524)
				(type default)
			)
			(layer "F.SilkS")
		)
		(fp_line
			(start 1.2573 -2.1844)
			(end 1.2573 2.1844)
			(stroke
				(width 0.1524)
				(type default)
			)
			(layer "F.SilkS")
		)
		(fp_poly
			(pts
				(xy -1.5113 2.4384) (xy 1.5113 2.4384) (xy 1.5113 -2.4384) (xy -1.5113 -2.4384)
			)
			(stroke
				(width 0)
				(type default)
			)
			(fill no)
			(layer "F.CrtYd")
		)
		(fp_poly
			(pts
				(xy -1.5113 -2.4384) (xy 1.5113 -2.4384) (xy 1.5113 2.4384) (xy -1.5113 2.4384)
			)
			(stroke
				(width 0)
				(type default)
			)
			(fill no)
			(layer "F.Fab")
		)
		(pad "1" smd rect
			(at -0.75057 1.1684 270)
			(size 0.3048 1.524)
			(layers "F.Cu" "F.Mask" "F.Paste")
			(net "SAS_R_SDBRX")
		)
		(pad "2" smd rect
			(at -0.25019 1.1684 270)
			(size 0.3048 1.524)
			(layers "F.Cu" "F.Mask" "F.Paste")
			(net "GND")
		)
		(pad "3" smd rect
			(at 0.25019 1.1684 270)
			(size 0.3048 1.524)
			(layers "F.Cu" "F.Mask" "F.Paste")
			(net "P1V8_E")
		)
		(pad "4" smd rect
			(at 0.75057 1.1684 270)
			(size 0.3048 1.524)
			(layers "F.Cu" "F.Mask" "F.Paste")
			(net "SDB_RX_R")
		)
		(pad "5" smd rect
			(at 0.75057 -1.1684 270)
			(size 0.3048 1.524)
			(layers "F.Cu" "F.Mask" "F.Paste")
			(net "SDB_TX_R")
		)
		(pad "6" smd rect
			(at 0.25019 -1.1684 270)
			(size 0.3048 1.524)
			(layers "F.Cu" "F.Mask" "F.Paste")
			(net "SDB_UART_EN")
		)
		(pad "7" smd rect
			(at -0.25019 -1.1684 270)
			(size 0.3048 1.524)
			(layers "F.Cu" "F.Mask" "F.Paste")
			(net "P3V3")
		)
		(pad "8" smd rect
			(at -0.75057 -1.1684 270)
			(size 0.3048 1.524)
			(layers "F.Cu" "F.Mask" "F.Paste")
			(net "SAS_R_SDBTX")
		)
	)
	(footprint ""
		(layer "F.Cu")
		(at 159.52978 -118.98122 90)
		(property "Reference" "R31"
			(at 0 0 90)
			(layer "F.SilkS")
			(hide yes)
			(effects
				(font
					(size 1.27 1.27)
				)
			)
		)
		(property "Value" "475KR2F-GP"
			(at 0.064008 -3.993896 90)
			(unlocked yes)
			(layer "F.Fab")
			(hide yes)
			(effects
				(font
					(size 1.016 1.016)
					(thickness 0.1524)
				)
			)
		)
		(property "Device Type" "R402H16"
			(at 0.064008 -5.517896 90)
			(unlocked yes)
			(layer "F.Fab")
			(hide yes)
			(effects
				(font
					(size 1.016 1.016)
					(thickness 0.1524)
				)
			)
		)
		(duplicate_pad_numbers_are_jumpers no)
		(fp_line
			(start 0.508 -0.9398)
			(end -0.508 -0.9398)
			(stroke
				(width 0.1524)
				(type default)
			)
			(layer "F.SilkS")
		)
		(fp_line
			(start -0.508 -0.9398)
			(end -0.508 0.9398)
			(stroke
				(width 0.1524)
				(type default)
			)
			(layer "F.SilkS")
		)
		(fp_rect
			(start -0.508 0.9398)
			(end 0.508 -0.9398)
			(stroke
				(width 0)
				(type default)
			)
			(fill no)
			(layer "F.CrtYd")
		)
		(fp_rect
			(start -0.508 0.9398)
			(end 0.508 -0.9398)
			(stroke
				(width 0)
				(type default)
			)
			(fill no)
			(layer "F.Fab")
		)
		(pad "1" smd custom
			(at 0 -0.4445 90)
			(size 0.1397 0.1397)
			(layers "F.Cu" "F.Mask" "F.Paste")
			(net "P1V5_E_MODE")
			(options
				(clearance outline)
				(anchor circle)
			)
			(primitives
				(gr_poly
					(pts
						(arc
							(start -0.1778 -0.2794)
							(mid -0.249642 -0.249642)
							(end -0.2794 -0.1778)
						)
						(arc
							(start -0.2794 0.1778)
							(mid -0.249642 0.249642)
							(end -0.1778 0.2794)
						)
						(arc
							(start 0.1778 0.2794)
							(mid 0.249642 0.249642)
							(end 0.2794 0.1778)
						)
						(arc
							(start 0.2794 -0.1778)
							(mid 0.249642 -0.249642)
							(end 0.1778 -0.2794)
						)
					)
					(width 0)
					(fill yes)
				)
			)
		)
		(pad "2" smd custom
			(at 0 0.4445 90)
			(size 0.1397 0.1397)
			(layers "F.Cu" "F.Mask" "F.Paste")
			(net "P1V5_E_PG")
			(options
				(clearance outline)
				(anchor circle)
			)
			(primitives
				(gr_poly
					(pts
						(arc
							(start -0.1778 -0.2794)
							(mid -0.249642 -0.249642)
							(end -0.2794 -0.1778)
						)
						(arc
							(start -0.2794 0.1778)
							(mid -0.249642 0.249642)
							(end -0.1778 0.2794)
						)
						(arc
							(start 0.1778 0.2794)
							(mid 0.249642 0.249642)
							(end 0.2794 0.1778)
						)
						(arc
							(start 0.2794 -0.1778)
							(mid 0.249642 -0.249642)
							(end 0.1778 -0.2794)
						)
					)
					(width 0)
					(fill yes)
				)
			)
		)
	)
	(footprint ""
		(layer "F.Cu")
		(at 146.37131 -46.469554 102)
		(property "Reference" "C340"
			(at 0 0 102)
			(layer "F.SilkS")
			(hide yes)
			(effects
				(font
					(size 1.27 1.27)
				)
			)
		)
		(property "Value" "SCD01U16V1KX-GP"
			(at -2.832296 -1.73983 102)
			(unlocked yes)
			(layer "F.Fab")
			(hide yes)
			(effects
				(font
					(size 1.016 1.016)
					(thickness 0.1524)
				)
			)
		)
		(property "Device Type" "C0201H13"
			(at -2.832174 -3.263834 102)
			(unlocked yes)
			(layer "F.Fab")
			(hide yes)
			(effects
				(font
					(size 1.016 1.016)
					(thickness 0.1524)
				)
			)
		)
		(duplicate_pad_numbers_are_jumpers no)
		(fp_poly
			(pts
				(xy -0.279454 -0.647706) (xy 0.279346 -0.647706) (xy 0.279346 0.647694) (xy -0.279454 0.647694)
			)
			(stroke
				(width 0)
				(type default)
			)
			(fill no)
			(layer "F.CrtYd")
		)
		(fp_poly
			(pts
				(xy -0.279454 -0.647706) (xy 0.279346 -0.647706) (xy 0.279346 0.647694) (xy -0.279454 0.647694)
			)
			(stroke
				(width 0)
				(type default)
			)
			(fill no)
			(layer "F.Fab")
		)
		(pad "1" smd custom
			(at -0.000001 -0.2794 102)
			(size 0.0762 0.0762)
			(layers "F.Cu" "F.Mask" "F.Paste")
			(net "PHY_SCC_TO_IOC_45_DN")
			(options
				(clearance outline)
				(anchor circle)
			)
			(primitives
				(gr_poly
					(pts
						(arc
							(start 0.1524 -0.127)
							(mid 0.137521 -0.162921)
							(end 0.1016 -0.1778)
						)
						(arc
							(start -0.1016 -0.1778)
							(mid -0.137521 -0.162921)
							(end -0.1524 -0.127)
						)
						(arc
							(start -0.1524 0.127)
							(mid -0.137521 0.162921)
							(end -0.1016 0.1778)
						)
						(arc
							(start 0.1016 0.1778)
							(mid 0.137521 0.162921)
							(end 0.1524 0.127)
						)
					)
					(width 0)
					(fill yes)
				)
			)
		)
		(pad "2" smd custom
			(at 0.000001 0.2794 102)
			(size 0.0762 0.0762)
			(layers "F.Cu" "F.Mask" "F.Paste")
			(net "PHY_SCC_TO_IOC_C_45_DN")
			(options
				(clearance outline)
				(anchor circle)
			)
			(primitives
				(gr_poly
					(pts
						(arc
							(start 0.1524 -0.127)
							(mid 0.137521 -0.162921)
							(end 0.1016 -0.1778)
						)
						(arc
							(start -0.1016 -0.1778)
							(mid -0.137521 -0.162921)
							(end -0.1524 -0.127)
						)
						(arc
							(start -0.1524 0.127)
							(mid -0.137521 0.162921)
							(end -0.1016 0.1778)
						)
						(arc
							(start 0.1016 0.1778)
							(mid 0.137521 0.162921)
							(end 0.1524 0.127)
						)
					)
					(width 0)
					(fill yes)
				)
			)
		)
	)
	(footprint ""
		(layer "F.Cu")
		(at 148.473668 -50.973736 -78)
		(property "Reference" "VIA23"
			(at 0 0 282)
			(layer "F.SilkS")
			(hide yes)
			(effects
				(font
					(size 1.27 1.27)
				)
			)
		)
		(property "Value" "100OHM-8L-1D6MM-L13-GP"
			(at 3.289333 0.050849 282)
			(unlocked yes)
			(layer "F.Fab")
			(hide yes)
			(effects
				(font
					(size 1.016 1.016)
					(thickness 0.1524)
				)
			)
		)
		(property "Device Type" "VIA-PCIE-4P-409091"
			(at 3.289456 -1.473155 282)
			(unlocked yes)
			(layer "F.Fab")
			(hide yes)
			(effects
				(font
					(size 1.016 1.016)
					(thickness 0.1524)
				)
			)
		)
		(duplicate_pad_numbers_are_jumpers no)
		(fp_poly
			(pts
				(xy -2.044719 -0.457296) (xy 2.04468 -0.457296) (xy 2.044681 0.457104) (xy -2.044719 0.457104)
			)
			(stroke
				(width 0)
				(type default)
			)
			(fill no)
			(layer "F.CrtYd")
		)
		(fp_poly
			(pts
				(xy -2.044719 -0.457296) (xy 2.04468 -0.457296) (xy 2.044681 0.457104) (xy -2.044719 0.457104)
			)
			(stroke
				(width 0)
				(type default)
			)
			(fill no)
			(layer "F.Fab")
		)
		(pad "1" thru_hole circle
			(at -1.5875 0 282)
			(size 0.508 0.508)
			(drill 0.254)
			(layers "*.Cu" "*.Mask")
			(remove_unused_layers no)
			(net "GND")
			(clearance 0.2032)
			(thermal_gap 0.2032)
		)
		(pad "2" thru_hole circle
			(at -0.5715 0.000001 282)
			(size 0.508 0.508)
			(drill 0.254)
			(layers "*.Cu" "*.Mask")
			(remove_unused_layers no)
			(net "PHY_SCC_TO_IOC_C_46_DP")
			(clearance 0.2032)
			(thermal_gap 0.2032)
		)
		(pad "3" thru_hole circle
			(at 0.5715 -0.000001 282)
			(size 0.508 0.508)
			(drill 0.254)
			(layers "*.Cu" "*.Mask")
			(remove_unused_layers no)
			(net "PHY_SCC_TO_IOC_C_46_DN")
			(clearance 0.2032)
			(thermal_gap 0.2032)
		)
		(pad "4" thru_hole circle
			(at 1.5875 0 282)
			(size 0.508 0.508)
			(drill 0.254)
			(layers "*.Cu" "*.Mask")
			(remove_unused_layers no)
			(net "GND")
			(clearance 0.2032)
			(thermal_gap 0.2032)
		)
	)
	(footprint ""
		(layer "F.Cu")
		(at 7.2898 -74.2188 -90)
		(property "Reference" "R360"
			(at 0 0 270)
			(layer "F.SilkS")
			(hide yes)
			(effects
				(font
					(size 1.27 1.27)
				)
			)
		)
		(property "Value" "4K7R2F-GP"
			(at 0.064008 -3.993896 270)
			(unlocked yes)
			(layer "F.Fab")
			(hide yes)
			(effects
				(font
					(size 1.016 1.016)
					(thickness 0.1524)
				)
			)
		)
		(property "Device Type" "R402H16"
			(at 0.064008 -5.517896 270)
			(unlocked yes)
			(layer "F.Fab")
			(hide yes)
			(effects
				(font
					(size 1.016 1.016)
					(thickness 0.1524)
				)
			)
		)
		(duplicate_pad_numbers_are_jumpers no)
		(fp_line
			(start -0.508 -0.9398)
			(end -0.508 0.9398)
			(stroke
				(width 0.1524)
				(type default)
			)
			(layer "F.SilkS")
		)
		(fp_line
			(start 0.508 -0.9398)
			(end -0.508 -0.9398)
			(stroke
				(width 0.1524)
				(type default)
			)
			(layer "F.SilkS")
		)
		(fp_rect
			(start -0.508 0.9398)
			(end 0.508 -0.9398)
			(stroke
				(width 0)
				(type default)
			)
			(fill no)
			(layer "F.CrtYd")
		)
		(fp_rect
			(start -0.508 0.9398)
			(end 0.508 -0.9398)
			(stroke
				(width 0)
				(type default)
			)
			(fill no)
			(layer "F.Fab")
		)
		(pad "1" smd custom
			(at 0 -0.4445 270)
			(size 0.1397 0.1397)
			(layers "F.Cu" "F.Mask" "F.Paste")
			(net "FRU_EEPROM_A0")
			(options
				(clearance outline)
				(anchor circle)
			)
			(primitives
				(gr_poly
					(pts
						(arc
							(start -0.1778 -0.2794)
							(mid -0.249642 -0.249642)
							(end -0.2794 -0.1778)
						)
						(arc
							(start -0.2794 0.1778)
							(mid -0.249642 0.249642)
							(end -0.1778 0.2794)
						)
						(arc
							(start 0.1778 0.2794)
							(mid 0.249642 0.249642)
							(end 0.2794 0.1778)
						)
						(arc
							(start 0.2794 -0.1778)
							(mid 0.249642 -0.249642)
							(end 0.1778 -0.2794)
						)
					)
					(width 0)
					(fill yes)
				)
			)
		)
		(pad "2" smd custom
			(at 0 0.4445 270)
			(size 0.1397 0.1397)
			(layers "F.Cu" "F.Mask" "F.Paste")
			(net "GND")
			(options
				(clearance outline)
				(anchor circle)
			)
			(primitives
				(gr_poly
					(pts
						(arc
							(start -0.1778 -0.2794)
							(mid -0.249642 -0.249642)
							(end -0.2794 -0.1778)
						)
						(arc
							(start -0.2794 0.1778)
							(mid -0.249642 0.249642)
							(end -0.1778 0.2794)
						)
						(arc
							(start 0.1778 0.2794)
							(mid 0.249642 0.249642)
							(end 0.2794 0.1778)
						)
						(arc
							(start 0.2794 -0.1778)
							(mid 0.249642 -0.249642)
							(end 0.1778 -0.2794)
						)
					)
					(width 0)
					(fill yes)
				)
			)
		)
	)
)
